(kicad_pcb
	(version 20260206)
	(generator "pcbnew")
	(generator_version "10.0")
	(general
		(thickness 1.6)
		(legacy_teardrops no)
	)
	(paper "A4")
	(title_block
		(title "pdpb — Lightning_PDPB_BRD.brd")
		(comment 1 "Lightning (Wiwynn / Facebook NVMe JBOF) / footprints 551-557 of 1140")
	)
	(layers
		(0 "F.Cu" signal "TOP")
		(4 "In1.Cu" signal "L2GND")
		(6 "In2.Cu" signal "L3")
		(8 "In3.Cu" signal "L4VCC")
		(10 "In4.Cu" signal "L5VCC")
		(12 "In5.Cu" signal "L6")
		(14 "In6.Cu" signal "L7GND")
		(2 "B.Cu" signal "BOTTOM")
		(9 "F.Adhes" user "F.Adhesive")
		(11 "B.Adhes" user "B.Adhesive")
		(13 "F.Paste" user "Package Geometry/Pastemask Top")
		(15 "B.Paste" user "Package Geometry/Pastemask Bottom")
		(5 "F.SilkS" user "Ref Des/Silkscreen Top")
		(7 "B.SilkS" user "Ref Des/Silkscreen Bottom")
		(1 "F.Mask" user "Board Geometry/Soldermask Top")
		(3 "B.Mask" user "Board Geometry/Soldermask Bottom")
		(17 "Dwgs.User" user "User.Drawings")
		(19 "Cmts.User" user "User.Comments")
		(21 "Eco1.User" user "User.Eco1")
		(23 "Eco2.User" user "User.Eco2")
		(25 "Edge.Cuts" user "Board Geometry/Outline")
		(27 "Margin" user)
		(31 "F.CrtYd" user "Package Geometry/Place Bound Top")
		(29 "B.CrtYd" user "Package Geometry/Place Bound Bottom")
		(35 "F.Fab" user "Ref Des/Assembly Top")
		(33 "B.Fab" user "Ref Des/Assembly Bottom")
	)
	(footprint ""
		(layer "F.Cu")
		(at 107.442 -205.613 -90)
		(property "Reference" "R9594"
			(at 0 0 270)
			(layer "F.SilkS")
			(hide yes)
			(effects
				(font
					(size 1.27 1.27)
				)
			)
		)
		(property "Value" "10R2F-L-GP"
			(at 0.064008 -3.993896 270)
			(unlocked yes)
			(layer "F.Fab")
			(hide yes)
			(effects
				(font
					(size 1.016 1.016)
					(thickness 0.1524)
				)
			)
		)
		(property "Device Type" "R402H14"
			(at 0.064008 -5.517896 270)
			(unlocked yes)
			(layer "F.Fab")
			(hide yes)
			(effects
				(font
					(size 1.016 1.016)
					(thickness 0.1524)
				)
			)
		)
		(duplicate_pad_numbers_are_jumpers no)
		(fp_line
			(start -0.508 -0.9398)
			(end -0.508 0.9398)
			(stroke
				(width 0.1524)
				(type default)
			)
			(layer "F.SilkS")
		)
		(fp_line
			(start 0.508 -0.9398)
			(end -0.508 -0.9398)
			(stroke
				(width 0.1524)
				(type default)
			)
			(layer "F.SilkS")
		)
		(fp_rect
			(start -0.508 0.9398)
			(end 0.508 -0.9398)
			(stroke
				(width 0)
				(type default)
			)
			(fill no)
			(layer "F.CrtYd")
		)
		(fp_rect
			(start -0.508 0.9398)
			(end 0.508 -0.9398)
			(stroke
				(width 0)
				(type default)
			)
			(fill no)
			(layer "F.Fab")
		)
		(pad "1" smd custom
			(at 0 -0.4445 270)
			(size 0.1397 0.1397)
			(layers "F.Cu" "F.Mask" "F.Paste")
			(net "SSD_PRSNT_NET3")
			(options
				(clearance outline)
				(anchor circle)
			)
			(primitives
				(gr_poly
					(pts
						(arc
							(start -0.1778 -0.2794)
							(mid -0.249642 -0.249642)
							(end -0.2794 -0.1778)
						)
						(arc
							(start -0.2794 0.1778)
							(mid -0.249642 0.249642)
							(end -0.1778 0.2794)
						)
						(arc
							(start 0.1778 0.2794)
							(mid 0.249642 0.249642)
							(end 0.2794 0.1778)
						)
						(arc
							(start 0.2794 -0.1778)
							(mid 0.249642 -0.249642)
							(end 0.1778 -0.2794)
						)
					)
					(width 0)
					(fill yes)
				)
			)
		)
		(pad "2" smd custom
			(at 0 0.4445 270)
			(size 0.1397 0.1397)
			(layers "F.Cu" "F.Mask" "F.Paste")
			(net "SSD_PRSNT3")
			(options
				(clearance outline)
				(anchor circle)
			)
			(primitives
				(gr_poly
					(pts
						(arc
							(start -0.1778 -0.2794)
							(mid -0.249642 -0.249642)
							(end -0.2794 -0.1778)
						)
						(arc
							(start -0.2794 0.1778)
							(mid -0.249642 0.249642)
							(end -0.1778 0.2794)
						)
						(arc
							(start 0.1778 0.2794)
							(mid 0.249642 0.249642)
							(end 0.2794 0.1778)
						)
						(arc
							(start 0.2794 -0.1778)
							(mid 0.249642 -0.249642)
							(end 0.1778 -0.2794)
						)
					)
					(width 0)
					(fill yes)
				)
			)
		)
	)
	(footprint ""
		(layer "F.Cu")
		(at 35.56 -205.0034 90)
		(property "Reference" "Q87"
			(at 0 0 90)
			(layer "F.SilkS")
			(hide yes)
			(effects
				(font
					(size 1.27 1.27)
				)
			)
		)
		(property "Value" "2N7002A-7-GP"
			(at 0.127 -8.9662 90)
			(unlocked yes)
			(layer "F.Fab")
			(hide yes)
			(effects
				(font
					(size 1.016 1.016)
					(thickness 0.1524)
				)
			)
		)
		(property "Device Type" "SOT23DGS2D4H48"
			(at 0.127 -10.4902 90)
			(unlocked yes)
			(layer "F.Fab")
			(hide yes)
			(effects
				(font
					(size 1.016 1.016)
					(thickness 0.1524)
				)
			)
		)
		(duplicate_pad_numbers_are_jumpers no)
		(fp_line
			(start 1.651 -1.778)
			(end -1.651 -1.778)
			(stroke
				(width 0.1524)
				(type default)
			)
			(layer "F.SilkS")
		)
		(fp_line
			(start -1.651 -1.778)
			(end -1.651 1.778)
			(stroke
				(width 0.1524)
				(type default)
			)
			(layer "F.SilkS")
		)
		(fp_line
			(start 1.651 1.778)
			(end 1.651 -1.778)
			(stroke
				(width 0.1524)
				(type default)
			)
			(layer "F.SilkS")
		)
		(fp_line
			(start -1.651 1.778)
			(end 1.651 1.778)
			(stroke
				(width 0.1524)
				(type default)
			)
			(layer "F.SilkS")
		)
		(fp_poly
			(pts
				(xy -1.778 1.8796) (xy -1.778 -1.8796) (xy 1.778 -1.8796) (xy 1.778 1.8796)
			)
			(stroke
				(width 0)
				(type default)
			)
			(fill no)
			(layer "F.CrtYd")
		)
		(fp_poly
			(pts
				(xy -1.778 1.8796) (xy -1.778 -1.8796) (xy 1.778 -1.8796) (xy 1.778 1.8796)
			)
			(stroke
				(width 0)
				(type default)
			)
			(fill no)
			(layer "F.Fab")
		)
		(pad "D" smd custom
			(at 0 -0.9525 90)
			(size 0.1905 0.1905)
			(layers "F.Cu" "F.Mask" "F.Paste")
			(net "P12V_MOST12_GATE")
			(options
				(clearance outline)
				(anchor circle)
			)
			(primitives
				(gr_poly
					(pts
						(arc
							(start -0.1778 0.5715)
							(mid -0.321484 0.511984)
							(end -0.381 0.3683)
						)
						(arc
							(start -0.381 -0.3683)
							(mid -0.321484 -0.511984)
							(end -0.1778 -0.5715)
						)
						(arc
							(start 0.1778 -0.5715)
							(mid 0.321484 -0.511984)
							(end 0.381 -0.3683)
						)
						(arc
							(start 0.381 0.3683)
							(mid 0.321484 0.511984)
							(end 0.1778 0.5715)
						)
					)
					(width 0)
					(fill yes)
				)
			)
		)
		(pad "G" smd custom
			(at -0.98425 0.9525 90)
			(size 0.1905 0.1905)
			(layers "F.Cu" "F.Mask" "F.Paste")
			(net "SSD12_PWREN_R")
			(options
				(clearance outline)
				(anchor circle)
			)
			(primitives
				(gr_poly
					(pts
						(arc
							(start -0.1778 0.5715)
							(mid -0.321484 0.511984)
							(end -0.381 0.3683)
						)
						(arc
							(start -0.381 -0.3683)
							(mid -0.321484 -0.511984)
							(end -0.1778 -0.5715)
						)
						(arc
							(start 0.1778 -0.5715)
							(mid 0.321484 -0.511984)
							(end 0.381 -0.3683)
						)
						(arc
							(start 0.381 0.3683)
							(mid 0.321484 0.511984)
							(end 0.1778 0.5715)
						)
					)
					(width 0)
					(fill yes)
				)
			)
		)
		(pad "S" smd custom
			(at 0.98425 0.9525 90)
			(size 0.1905 0.1905)
			(layers "F.Cu" "F.Mask" "F.Paste")
			(net "GND")
			(options
				(clearance outline)
				(anchor circle)
			)
			(primitives
				(gr_poly
					(pts
						(arc
							(start -0.1778 0.5715)
							(mid -0.321484 0.511984)
							(end -0.381 0.3683)
						)
						(arc
							(start -0.381 -0.3683)
							(mid -0.321484 -0.511984)
							(end -0.1778 -0.5715)
						)
						(arc
							(start 0.1778 -0.5715)
							(mid 0.321484 -0.511984)
							(end 0.381 -0.3683)
						)
						(arc
							(start 0.381 0.3683)
							(mid 0.321484 0.511984)
							(end 0.1778 0.5715)
						)
					)
					(width 0)
					(fill yes)
				)
			)
		)
	)
	(footprint ""
		(layer "F.Cu")
		(at 209.296 -396.113 180)
		(property "Reference" "R567"
			(at 0 0 180)
			(layer "F.SilkS")
			(hide yes)
			(effects
				(font
					(size 1.27 1.27)
				)
			)
		)
		(property "Value" "300KR2F-GP"
			(at 0.064008 -3.993896 180)
			(unlocked yes)
			(layer "F.Fab")
			(hide yes)
			(effects
				(font
					(size 1.016 1.016)
					(thickness 0.1524)
				)
			)
		)
		(property "Device Type" "R402H16"
			(at 0.064008 -5.517896 180)
			(unlocked yes)
			(layer "F.Fab")
			(hide yes)
			(effects
				(font
					(size 1.016 1.016)
					(thickness 0.1524)
				)
			)
		)
		(duplicate_pad_numbers_are_jumpers no)
		(fp_line
			(start 0.508 -0.9398)
			(end -0.508 -0.9398)
			(stroke
				(width 0.1524)
				(type default)
			)
			(layer "F.SilkS")
		)
		(fp_line
			(start -0.508 -0.9398)
			(end -0.508 0.9398)
			(stroke
				(width 0.1524)
				(type default)
			)
			(layer "F.SilkS")
		)
		(fp_rect
			(start -0.508 0.9398)
			(end 0.508 -0.9398)
			(stroke
				(width 0)
				(type default)
			)
			(fill no)
			(layer "F.CrtYd")
		)
		(fp_rect
			(start -0.508 0.9398)
			(end 0.508 -0.9398)
			(stroke
				(width 0)
				(type default)
			)
			(fill no)
			(layer "F.Fab")
		)
		(pad "1" smd custom
			(at 0 -0.4445 180)
			(size 0.1397 0.1397)
			(layers "F.Cu" "F.Mask" "F.Paste")
			(net "SW_SSD1_N")
			(options
				(clearance outline)
				(anchor circle)
			)
			(primitives
				(gr_poly
					(pts
						(arc
							(start -0.1778 -0.2794)
							(mid -0.249642 -0.249642)
							(end -0.2794 -0.1778)
						)
						(arc
							(start -0.2794 0.1778)
							(mid -0.249642 0.249642)
							(end -0.1778 0.2794)
						)
						(arc
							(start 0.1778 0.2794)
							(mid 0.249642 0.249642)
							(end 0.2794 0.1778)
						)
						(arc
							(start 0.2794 -0.1778)
							(mid 0.249642 -0.249642)
							(end 0.1778 -0.2794)
						)
					)
					(width 0)
					(fill yes)
				)
			)
		)
		(pad "2" smd custom
			(at 0 0.4445 180)
			(size 0.1397 0.1397)
			(layers "F.Cu" "F.Mask" "F.Paste")
			(net "P12V")
			(options
				(clearance outline)
				(anchor circle)
			)
			(primitives
				(gr_poly
					(pts
						(arc
							(start -0.1778 -0.2794)
							(mid -0.249642 -0.249642)
							(end -0.2794 -0.1778)
						)
						(arc
							(start -0.2794 0.1778)
							(mid -0.249642 0.249642)
							(end -0.1778 0.2794)
						)
						(arc
							(start 0.1778 0.2794)
							(mid 0.249642 0.249642)
							(end 0.2794 0.1778)
						)
						(arc
							(start 0.2794 -0.1778)
							(mid 0.249642 -0.249642)
							(end 0.1778 -0.2794)
						)
					)
					(width 0)
					(fill yes)
				)
			)
		)
	)
	(footprint ""
		(layer "F.Cu")
		(at 79.1718 -216.6874 90)
		(property "Reference" "FB9"
			(at 0 0 90)
			(layer "F.SilkS")
			(hide yes)
			(effects
				(font
					(size 1.27 1.27)
				)
			)
		)
		(property "Value" "BLM21PG331SN1D-2-GP"
			(at 0 -4.2418 90)
			(unlocked yes)
			(layer "F.Fab")
			(hide yes)
			(effects
				(font
					(size 1.016 1.016)
					(thickness 0.1524)
				)
			)
		)
		(property "Device Type" "L805H42"
			(at 0 -5.7912 90)
			(unlocked yes)
			(layer "F.Fab")
			(hide yes)
			(effects
				(font
					(size 1.016 1.016)
					(thickness 0.1524)
				)
			)
		)
		(duplicate_pad_numbers_are_jumpers no)
		(fp_line
			(start 0.889 -1.7018)
			(end 0.889 1.7018)
			(stroke
				(width 0.1524)
				(type default)
			)
			(layer "F.SilkS")
		)
		(fp_line
			(start -0.889 -1.7018)
			(end 0.889 -1.7018)
			(stroke
				(width 0.1524)
				(type default)
			)
			(layer "F.SilkS")
		)
		(fp_line
			(start 0.889 1.7018)
			(end -0.889 1.7018)
			(stroke
				(width 0.1524)
				(type default)
			)
			(layer "F.SilkS")
		)
		(fp_line
			(start -0.889 1.7018)
			(end -0.889 -1.7018)
			(stroke
				(width 0.1524)
				(type default)
			)
			(layer "F.SilkS")
		)
		(fp_rect
			(start -0.9652 1.778)
			(end 0.9652 -1.778)
			(stroke
				(width 0)
				(type default)
			)
			(fill no)
			(layer "F.CrtYd")
		)
		(fp_rect
			(start -0.9652 1.778)
			(end 0.9652 -1.778)
			(stroke
				(width 0)
				(type default)
			)
			(fill no)
			(layer "F.Fab")
		)
		(pad "1" smd rect
			(at 0 -0.9652 90)
			(size 1.397 1.143)
			(layers "F.Cu" "F.Mask" "F.Paste")
			(net "P3V3")
		)
		(pad "2" smd rect
			(at 0 0.9652 90)
			(size 1.397 1.143)
			(layers "F.Cu" "F.Mask" "F.Paste")
			(net "VDD_DIFF_3")
		)
	)
	(footprint ""
		(layer "F.Cu")
		(at 227.203 -137.91311 90)
		(property "Reference" "U200"
			(at 0 0 90)
			(layer "F.SilkS")
			(hide yes)
			(effects
				(font
					(size 1.27 1.27)
				)
			)
		)
		(property "Value" "SN74LVC1G08DCKR-GP"
			(at -2.3368 -8.6868 90)
			(unlocked yes)
			(layer "F.Fab")
			(hide yes)
			(effects
				(font
					(size 1.016 1.016)
					(thickness 0.1524)
				)
			)
		)
		(property "Device Type" "SC70-5H44"
			(at -2.3114 -10.414 90)
			(unlocked yes)
			(layer "F.Fab")
			(hide yes)
			(effects
				(font
					(size 1.016 1.016)
					(thickness 0.1524)
				)
			)
		)
		(duplicate_pad_numbers_are_jumpers no)
		(fp_line
			(start 1.3843 -1.8034)
			(end 1.3843 -1.1176)
			(stroke
				(width 0.3302)
				(type default)
			)
			(layer "F.SilkS")
		)
		(fp_line
			(start 0.6604 -1.8034)
			(end 1.3843 -1.8034)
			(stroke
				(width 0.3302)
				(type default)
			)
			(layer "F.SilkS")
		)
		(fp_line
			(start 1.27 -1.7018)
			(end 1.27 1.7018)
			(stroke
				(width 0.1524)
				(type default)
			)
			(layer "F.SilkS")
		)
		(fp_line
			(start -1.27 -1.7018)
			(end 1.27 -1.7018)
			(stroke
				(width 0.1524)
				(type default)
			)
			(layer "F.SilkS")
		)
		(fp_line
			(start 1.27 1.7018)
			(end -1.27 1.7018)
			(stroke
				(width 0.1524)
				(type default)
			)
			(layer "F.SilkS")
		)
		(fp_line
			(start -1.27 1.7018)
			(end -1.27 -1.7018)
			(stroke
				(width 0.1524)
				(type default)
			)
			(layer "F.SilkS")
		)
		(fp_rect
			(start -1.524 1.9558)
			(end 1.524 -1.9558)
			(stroke
				(width 0)
				(type default)
			)
			(fill no)
			(layer "F.CrtYd")
		)
		(fp_poly
			(pts
				(xy -1.524 -1.9558) (xy 1.524 -1.9558) (xy 1.524 1.9558) (xy -1.524 1.9558)
			)
			(stroke
				(width 0)
				(type default)
			)
			(fill no)
			(layer "F.Fab")
		)
		(pad "1" smd rect
			(at 0.65024 -0.8255 90)
			(size 0.4064 1.2192)
			(layers "F.Cu" "F.Mask" "F.Paste")
			(net "SSD3_CLK0_OE_MOS_N")
		)
		(pad "2" smd rect
			(at 0 -0.8255 90)
			(size 0.4064 1.2192)
			(layers "F.Cu" "F.Mask" "F.Paste")
			(net "ATTN_LED_DR3_N")
		)
		(pad "3" smd rect
			(at -0.65024 -0.8255 90)
			(size 0.4064 1.2192)
			(layers "F.Cu" "F.Mask" "F.Paste")
			(net "GND")
		)
		(pad "4" smd rect
			(at -0.65024 0.8255 90)
			(size 0.4064 1.2192)
			(layers "F.Cu" "F.Mask" "F.Paste")
			(net "ATTN_LED_DR3_AND")
		)
		(pad "5" smd rect
			(at 0.65024 0.8255 90)
			(size 0.4064 1.2192)
			(layers "F.Cu" "F.Mask" "F.Paste")
			(net "P3V3")
		)
	)
	(footprint ""
		(layer "F.Cu")
		(at 29.845 -424.434 90)
		(property "Reference" "R408"
			(at 0 0 90)
			(layer "F.SilkS")
			(hide yes)
			(effects
				(font
					(size 1.27 1.27)
				)
			)
		)
		(property "Value" "0R2J-2-GP"
			(at 0.064008 -3.993896 90)
			(unlocked yes)
			(layer "F.Fab")
			(hide yes)
			(effects
				(font
					(size 1.016 1.016)
					(thickness 0.1524)
				)
			)
		)
		(property "Device Type" "R402H16"
			(at 0.064008 -5.517896 90)
			(unlocked yes)
			(layer "F.Fab")
			(hide yes)
			(effects
				(font
					(size 1.016 1.016)
					(thickness 0.1524)
				)
			)
		)
		(duplicate_pad_numbers_are_jumpers no)
		(fp_line
			(start 0.508 -0.9398)
			(end -0.508 -0.9398)
			(stroke
				(width 0.1524)
				(type default)
			)
			(layer "F.SilkS")
		)
		(fp_line
			(start -0.508 -0.9398)
			(end -0.508 0.9398)
			(stroke
				(width 0.1524)
				(type default)
			)
			(layer "F.SilkS")
		)
		(fp_rect
			(start -0.508 0.9398)
			(end 0.508 -0.9398)
			(stroke
				(width 0)
				(type default)
			)
			(fill no)
			(layer "F.CrtYd")
		)
		(fp_rect
			(start -0.508 0.9398)
			(end 0.508 -0.9398)
			(stroke
				(width 0)
				(type default)
			)
			(fill no)
			(layer "F.Fab")
		)
		(pad "1" smd custom
			(at 0 -0.4445 90)
			(size 0.1397 0.1397)
			(layers "F.Cu" "F.Mask" "F.Paste")
			(net "SCL_DR10_R")
			(options
				(clearance outline)
				(anchor circle)
			)
			(primitives
				(gr_poly
					(pts
						(arc
							(start -0.1778 -0.2794)
							(mid -0.249642 -0.249642)
							(end -0.2794 -0.1778)
						)
						(arc
							(start -0.2794 0.1778)
							(mid -0.249642 0.249642)
							(end -0.1778 0.2794)
						)
						(arc
							(start 0.1778 0.2794)
							(mid 0.249642 0.249642)
							(end 0.2794 0.1778)
						)
						(arc
							(start 0.2794 -0.1778)
							(mid 0.249642 -0.249642)
							(end 0.1778 -0.2794)
						)
					)
					(width 0)
					(fill yes)
				)
			)
		)
		(pad "2" smd custom
			(at 0 0.4445 90)
			(size 0.1397 0.1397)
			(layers "F.Cu" "F.Mask" "F.Paste")
			(net "SCL_DR10")
			(options
				(clearance outline)
				(anchor circle)
			)
			(primitives
				(gr_poly
					(pts
						(arc
							(start -0.1778 -0.2794)
							(mid -0.249642 -0.249642)
							(end -0.2794 -0.1778)
						)
						(arc
							(start -0.2794 0.1778)
							(mid -0.249642 0.249642)
							(end -0.1778 0.2794)
						)
						(arc
							(start 0.1778 0.2794)
							(mid 0.249642 0.249642)
							(end 0.2794 0.1778)
						)
						(arc
							(start 0.2794 -0.1778)
							(mid 0.249642 -0.249642)
							(end 0.1778 -0.2794)
						)
					)
					(width 0)
					(fill yes)
				)
			)
		)
	)
	(footprint ""
		(layer "F.Cu")
		(at 85.471 -303.403 -90)
		(property "Reference" "R9093"
			(at 0 0 270)
			(layer "F.SilkS")
			(hide yes)
			(effects
				(font
					(size 1.27 1.27)
				)
			)
		)
		(property "Value" "4K7R2F-GP"
			(at 0.064008 -3.993896 270)
			(unlocked yes)
			(layer "F.Fab")
			(hide yes)
			(effects
				(font
					(size 1.016 1.016)
					(thickness 0.1524)
				)
			)
		)
		(property "Device Type" "R402H16"
			(at 0.064008 -5.517896 270)
			(unlocked yes)
			(layer "F.Fab")
			(hide yes)
			(effects
				(font
					(size 1.016 1.016)
					(thickness 0.1524)
				)
			)
		)
		(duplicate_pad_numbers_are_jumpers no)
		(fp_line
			(start -0.508 -0.9398)
			(end -0.508 0.9398)
			(stroke
				(width 0.1524)
				(type default)
			)
			(layer "F.SilkS")
		)
		(fp_line
			(start 0.508 -0.9398)
			(end -0.508 -0.9398)
			(stroke
				(width 0.1524)
				(type default)
			)
			(layer "F.SilkS")
		)
		(fp_rect
			(start -0.508 0.9398)
			(end 0.508 -0.9398)
			(stroke
				(width 0)
				(type default)
			)
			(fill no)
			(layer "F.CrtYd")
		)
		(fp_rect
			(start -0.508 0.9398)
			(end 0.508 -0.9398)
			(stroke
				(width 0)
				(type default)
			)
			(fill no)
			(layer "F.Fab")
		)
		(pad "1" smd custom
			(at 0 -0.4445 270)
			(size 0.1397 0.1397)
			(layers "F.Cu" "F.Mask" "F.Paste")
			(net "CLK_BUF_EU2_SMB_A0_TRI")
			(options
				(clearance outline)
				(anchor circle)
			)
			(primitives
				(gr_poly
					(pts
						(arc
							(start -0.1778 -0.2794)
							(mid -0.249642 -0.249642)
							(end -0.2794 -0.1778)
						)
						(arc
							(start -0.2794 0.1778)
							(mid -0.249642 0.249642)
							(end -0.1778 0.2794)
						)
						(arc
							(start 0.1778 0.2794)
							(mid 0.249642 0.249642)
							(end 0.2794 0.1778)
						)
						(arc
							(start 0.2794 -0.1778)
							(mid 0.249642 -0.249642)
							(end 0.1778 -0.2794)
						)
					)
					(width 0)
					(fill yes)
				)
			)
		)
		(pad "2" smd custom
			(at 0 0.4445 270)
			(size 0.1397 0.1397)
			(layers "F.Cu" "F.Mask" "F.Paste")
			(net "GND")
			(options
				(clearance outline)
				(anchor circle)
			)
			(primitives
				(gr_poly
					(pts
						(arc
							(start -0.1778 -0.2794)
							(mid -0.249642 -0.249642)
							(end -0.2794 -0.1778)
						)
						(arc
							(start -0.2794 0.1778)
							(mid -0.249642 0.249642)
							(end -0.1778 0.2794)
						)
						(arc
							(start 0.1778 0.2794)
							(mid 0.249642 0.249642)
							(end 0.2794 0.1778)
						)
						(arc
							(start 0.2794 -0.1778)
							(mid 0.249642 -0.249642)
							(end 0.1778 -0.2794)
						)
					)
					(width 0)
					(fill yes)
				)
			)
		)
	)
)
